(kicad_pcb
	(version 20260206)
	(generator "pcbnew")
	(generator_version "10.0")
	(general
		(thickness 1.6)
		(legacy_teardrops no)
	)
	(paper "A4")
	(title_block
		(title "01162023_DA0F0TEBIF0_F0T_Expander_BD_F_brd_V02_OCP.brd")
		(comment 1 "Grand Teton / footprints 6129-6130 of 9728")
	)
	(layers
		(0 "F.Cu" signal "TOP")
		(4 "In1.Cu" signal "GND")
		(6 "In2.Cu" signal "VCC")
		(8 "In3.Cu" signal "VCC1")
		(10 "In4.Cu" signal "GND1")
		(12 "In5.Cu" signal "IN1")
		(14 "In6.Cu" signal "GND2")
		(16 "In7.Cu" signal "IN2")
		(18 "In8.Cu" signal "GND3")
		(20 "In9.Cu" signal "IN3")
		(22 "In10.Cu" signal "GND4")
		(24 "In11.Cu" signal "IN4")
		(26 "In12.Cu" signal "GND5")
		(28 "In13.Cu" signal "IN5")
		(30 "In14.Cu" signal "GND6")
		(32 "In15.Cu" signal "IN6")
		(34 "In16.Cu" signal "GND7")
		(2 "B.Cu" signal "BOTTOM")
		(9 "F.Adhes" user "F.Adhesive")
		(11 "B.Adhes" user "B.Adhesive")
		(13 "F.Paste" user "Package Geometry/Pastemask Top")
		(15 "B.Paste" user "Package Geometry/Pastemask Bottom")
		(5 "F.SilkS" user "Ref Des/Silkscreen Top")
		(7 "B.SilkS" user "Ref Des/Silkscreen Bottom")
		(1 "F.Mask" user "Board Geometry/Soldermask Top")
		(3 "B.Mask" user "Board Geometry/Soldermask Bottom")
		(17 "Dwgs.User" user "User.Drawings")
		(19 "Cmts.User" user "User.Comments")
		(21 "Eco1.User" user "User.Eco1")
		(23 "Eco2.User" user "User.Eco2")
		(25 "Edge.Cuts" user "Board Geometry/Outline")
		(27 "Margin" user)
		(31 "F.CrtYd" user "Package Geometry/Place Bound Top")
		(29 "B.CrtYd" user "Package Geometry/Place Bound Bottom")
		(35 "F.Fab" user "Ref Des/Assembly Top")
		(33 "B.Fab" user "Ref Des/Assembly Bottom")
	)
	(footprint ""
		(layer "F.Cu")
		(at 271.164812 -26.785062 180)
		(property "Reference" "J39"
			(at 4.057142 -11.087862 90)
			(unlocked yes)
			(layer "F.SilkS")
			(effects
				(font
					(size 0.7874 0.5842)
					(thickness 0.1524)
				)
			)
		)
		(property "Value" ""
			(at 0 0 180)
			(layer "F.Fab")
			(effects
				(font
					(size 1.27 1.27)
				)
			)
		)
		(duplicate_pad_numbers_are_jumpers no)
		(fp_line
			(start 3.150108 12.115038)
			(end 1.529334 12.115038)
			(stroke
				(width 0.1524)
				(type default)
			)
			(layer "F.SilkS")
		)
		(fp_line
			(start 3.074924 12.014962)
			(end 1.632204 12.014962)
			(stroke
				(width 0.1524)
				(type default)
			)
			(layer "F.SilkS")
		)
		(fp_line
			(start 1.632204 -12.014962)
			(end 3.074924 -12.014962)
			(stroke
				(width 0.1524)
				(type default)
			)
			(layer "F.SilkS")
		)
		(fp_line
			(start 1.529334 -12.115038)
			(end 3.150108 -12.115038)
			(stroke
				(width 0.1524)
				(type default)
			)
			(layer "F.SilkS")
		)
		(fp_line
			(start -1.529334 12.115038)
			(end -3.150108 12.115038)
			(stroke
				(width 0.1524)
				(type default)
			)
			(layer "F.SilkS")
		)
		(fp_line
			(start -1.632204 12.014962)
			(end -3.074924 12.014962)
			(stroke
				(width 0.1524)
				(type default)
			)
			(layer "F.SilkS")
		)
		(fp_line
			(start -3.074924 -12.014962)
			(end -1.632204 -12.014962)
			(stroke
				(width 0.1524)
				(type default)
			)
			(layer "F.SilkS")
		)
		(fp_line
			(start -3.150108 -12.115038)
			(end -1.529334 -12.115038)
			(stroke
				(width 0.1524)
				(type default)
			)
			(layer "F.SilkS")
		)
		(fp_poly
			(pts
				(xy 3.34391 -8.694928) (xy 3.766312 -9.962642) (xy 4.61137 -9.117584)
			)
			(stroke
				(width 0)
				(type default)
			)
			(fill yes)
			(layer "F.SilkS")
		)
		(fp_line
			(start 3.074924 12.014962)
			(end -3.074924 12.014962)
			(stroke
				(width 0.1)
				(type default)
			)
			(layer "F.Fab")
		)
		(fp_line
			(start 3.074924 -12.014962)
			(end 3.074924 12.014962)
			(stroke
				(width 0.1)
				(type default)
			)
			(layer "F.Fab")
		)
		(fp_line
			(start -3.074924 12.014962)
			(end -3.074924 -12.014962)
			(stroke
				(width 0.1)
				(type default)
			)
			(layer "F.Fab")
		)
		(fp_line
			(start -3.074924 -12.014962)
			(end 3.074924 -12.014962)
			(stroke
				(width 0.1)
				(type default)
			)
			(layer "F.Fab")
		)
		(fp_poly
			(pts
				(xy 3.348736 -7.994904) (xy 4.543806 -8.592566) (xy 4.543806 -7.397496)
			)
			(stroke
				(width 0)
				(type default)
			)
			(fill yes)
			(layer "F.Fab")
		)
		(pad "" np_thru_hole circle
			(at -1.75006 -9.815068 90)
			(size 1.1176 1.1176)
			(drill 1.1176)
			(layers "*.Cu" "*.Mask")
			(clearance 0.381)
			(thermal_gap 0.381)
		)
		(pad "" np_thru_hole circle
			(at 0 9.815068 90)
			(size 1.1176 1.1176)
			(drill 1.1176)
			(layers "*.Cu" "*.Mask")
			(clearance 0.381)
			(thermal_gap 0.381)
		)
		(pad "A1" smd rect
			(at 2.29997 -7.994904 90)
			(size 0.381 1.27)
			(layers "F.Cu" "F.Mask" "F.Paste")
			(net "GND")
		)
		(pad "A2" smd rect
			(at 2.29997 -7.394956 90)
			(size 0.381 1.27)
			(layers "F.Cu" "F.Mask" "F.Paste")
			(net "GND")
		)
		(pad "A3" smd rect
			(at 2.29997 -6.795008 90)
			(size 0.381 1.27)
			(layers "F.Cu" "F.Mask" "F.Paste")
			(net "GND")
		)
		(pad "A4" smd rect
			(at 2.29997 -6.19506 90)
			(size 0.381 1.27)
			(layers "F.Cu" "F.Mask" "F.Paste")
			(net "GND")
		)
		(pad "A5" smd rect
			(at 2.29997 -5.595112 90)
			(size 0.381 1.27)
			(layers "F.Cu" "F.Mask" "F.Paste")
			(net "GND")
		)
		(pad "A6" smd rect
			(at 2.29997 -4.99491 90)
			(size 0.381 1.27)
			(layers "F.Cu" "F.Mask" "F.Paste")
			(net "GND")
		)
		(pad "A7" smd rect
			(at 2.29997 -4.394962 90)
			(size 0.381 1.27)
			(layers "F.Cu" "F.Mask" "F.Paste")
			(net "SMB_ISO_SSD9_R_SCL")
		)
		(pad "A8" smd rect
			(at 2.29997 -3.795014 90)
			(size 0.381 1.27)
			(layers "F.Cu" "F.Mask" "F.Paste")
			(net "SMB_ISO_SSD9_R_SDA")
		)
		(pad "A9" smd rect
			(at 2.29997 -3.195066 90)
			(size 0.381 1.27)
			(layers "F.Cu" "F.Mask" "F.Paste")
			(net "RST_SMB_SSD9_ISO_R_N")
		)
		(pad "A10" smd rect
			(at 2.29997 -2.595118 90)
			(size 0.381 1.27)
			(layers "F.Cu" "F.Mask" "F.Paste")
			(net "SSD9_LED_ISO_R_N")
		)
		(pad "A11" smd rect
			(at 2.29997 -1.994916 90)
			(size 0.381 1.27)
			(layers "F.Cu" "F.Mask" "F.Paste")
			(net "PU_CLKREQ9")
		)
		(pad "A12" smd rect
			(at 2.29997 -1.394968 90)
			(size 0.381 1.27)
			(layers "F.Cu" "F.Mask" "F.Paste")
			(net "PRSNT_SSD9_N")
		)
		(pad "A13" smd rect
			(at 2.29997 -0.79502 90)
			(size 0.381 1.27)
			(layers "F.Cu" "F.Mask" "F.Paste")
			(net "GND")
		)
		(pad "A14" smd rect
			(at 2.29997 -0.195072 90)
			(size 0.381 1.27)
			(layers "F.Cu" "F.Mask" "F.Paste")
			(net "Net_8495")
		)
		(pad "A15" smd rect
			(at 2.29997 0.404876 90)
			(size 0.381 1.27)
			(layers "F.Cu" "F.Mask" "F.Paste")
			(net "Net_8494")
		)
		(pad "A16" smd rect
			(at 2.29997 1.005078 90)
			(size 0.381 1.27)
			(layers "F.Cu" "F.Mask" "F.Paste")
			(net "GND")
		)
		(pad "A17" smd rect
			(at 2.29997 1.605026 90)
			(size 0.381 1.27)
			(layers "F.Cu" "F.Mask" "F.Paste")
			(net "P5E_PEX2_STN2_RX_DN<40>")
		)
		(pad "A18" smd rect
			(at 2.29997 2.204974 90)
			(size 0.381 1.27)
			(layers "F.Cu" "F.Mask" "F.Paste")
			(net "P5E_PEX2_STN2_RX_DP<40>")
		)
		(pad "A19" smd rect
			(at 2.29997 2.804922 90)
			(size 0.381 1.27)
			(layers "F.Cu" "F.Mask" "F.Paste")
			(net "GND")
		)
		(pad "A20" smd rect
			(at 2.29997 3.405124 90)
			(size 0.381 1.27)
			(layers "F.Cu" "F.Mask" "F.Paste")
			(net "P5E_PEX2_STN2_RX_DN<41>")
		)
		(pad "A21" smd rect
			(at 2.29997 4.005072 90)
			(size 0.381 1.27)
			(layers "F.Cu" "F.Mask" "F.Paste")
			(net "P5E_PEX2_STN2_RX_DP<41>")
		)
		(pad "A22" smd rect
			(at 2.29997 4.60502 90)
			(size 0.381 1.27)
			(layers "F.Cu" "F.Mask" "F.Paste")
			(net "GND")
		)
		(pad "A23" smd rect
			(at 2.29997 5.204968 90)
			(size 0.381 1.27)
			(layers "F.Cu" "F.Mask" "F.Paste")
			(net "P5E_PEX2_STN2_RX_DN<42>")
		)
		(pad "A24" smd rect
			(at 2.29997 5.804916 90)
			(size 0.381 1.27)
			(layers "F.Cu" "F.Mask" "F.Paste")
			(net "P5E_PEX2_STN2_RX_DP<42>")
		)
		(pad "A25" smd rect
			(at 2.29997 6.405118 90)
			(size 0.381 1.27)
			(layers "F.Cu" "F.Mask" "F.Paste")
			(net "GND")
		)
		(pad "A26" smd rect
			(at 2.29997 7.005066 90)
			(size 0.381 1.27)
			(layers "F.Cu" "F.Mask" "F.Paste")
			(net "P5E_PEX2_STN2_RX_DN<43>")
		)
		(pad "A27" smd rect
			(at 2.29997 7.605014 90)
			(size 0.381 1.27)
			(layers "F.Cu" "F.Mask" "F.Paste")
			(net "P5E_PEX2_STN2_RX_DP<43>")
		)
		(pad "A28" smd rect
			(at 2.29997 8.204962 90)
			(size 0.381 1.27)
			(layers "F.Cu" "F.Mask" "F.Paste")
			(net "GND")
		)
		(pad "B1" smd rect
			(at -2.29997 -7.994904 90)
			(size 0.381 1.27)
			(layers "F.Cu" "F.Mask" "F.Paste")
			(net "P12V_SSD9")
		)
		(pad "B2" smd rect
			(at -2.29997 -7.394956 90)
			(size 0.381 1.27)
			(layers "F.Cu" "F.Mask" "F.Paste")
			(net "P12V_SSD9")
		)
		(pad "B3" smd rect
			(at -2.29997 -6.795008 90)
			(size 0.381 1.27)
			(layers "F.Cu" "F.Mask" "F.Paste")
			(net "P12V_SSD9")
		)
		(pad "B4" smd rect
			(at -2.29997 -6.19506 90)
			(size 0.381 1.27)
			(layers "F.Cu" "F.Mask" "F.Paste")
			(net "P12V_SSD9")
		)
		(pad "B5" smd rect
			(at -2.29997 -5.595112 90)
			(size 0.381 1.27)
			(layers "F.Cu" "F.Mask" "F.Paste")
			(net "P12V_SSD9")
		)
		(pad "B6" smd rect
			(at -2.29997 -4.99491 90)
			(size 0.381 1.27)
			(layers "F.Cu" "F.Mask" "F.Paste")
			(net "P12V_SSD9")
		)
		(pad "B7" smd rect
			(at -2.29997 -4.394962 90)
			(size 0.381 1.27)
			(layers "F.Cu" "F.Mask" "F.Paste")
			(net "Net_8496")
		)
		(pad "B8" smd rect
			(at -2.29997 -3.795014 90)
			(size 0.381 1.27)
			(layers "F.Cu" "F.Mask" "F.Paste")
			(net "Net_8493")
		)
		(pad "B9" smd rect
			(at -2.29997 -3.195066 90)
			(size 0.381 1.27)
			(layers "F.Cu" "F.Mask" "F.Paste")
			(net "DUALPORT_N_SSD9")
		)
		(pad "B10" smd rect
			(at -2.29997 -2.595118 90)
			(size 0.381 1.27)
			(layers "F.Cu" "F.Mask" "F.Paste")
			(net "RST_SSD9_PERST_R_N")
		)
		(pad "B11" smd rect
			(at -2.29997 -1.994916 90)
			(size 0.381 1.27)
			(layers "F.Cu" "F.Mask" "F.Paste")
			(net "P3V3_SSD9")
		)
		(pad "B12" smd rect
			(at -2.29997 -1.394968 90)
			(size 0.381 1.27)
			(layers "F.Cu" "F.Mask" "F.Paste")
			(net "SSD9_PWRDIS_R")
		)
		(pad "B13" smd rect
			(at -2.29997 -0.79502 90)
			(size 0.381 1.27)
			(layers "F.Cu" "F.Mask" "F.Paste")
			(net "GND")
		)
		(pad "B14" smd rect
			(at -2.29997 -0.195072 90)
			(size 0.381 1.27)
			(layers "F.Cu" "F.Mask" "F.Paste")
			(net "CLK_100M_DB800ZL_SSD9_R_DN")
		)
		(pad "B15" smd rect
			(at -2.29997 0.404876 90)
			(size 0.381 1.27)
			(layers "F.Cu" "F.Mask" "F.Paste")
			(net "CLK_100M_DB800ZL_SSD9_R_DP")
		)
		(pad "B16" smd rect
			(at -2.29997 1.005078 90)
			(size 0.381 1.27)
			(layers "F.Cu" "F.Mask" "F.Paste")
			(net "GND")
		)
		(pad "B17" smd rect
			(at -2.29997 1.605026 90)
			(size 0.381 1.27)
			(layers "F.Cu" "F.Mask" "F.Paste")
			(net "P5E_PEX2_STN2_TX_C_DN<40>")
		)
		(pad "B18" smd rect
			(at -2.29997 2.204974 90)
			(size 0.381 1.27)
			(layers "F.Cu" "F.Mask" "F.Paste")
			(net "P5E_PEX2_STN2_TX_C_DP<40>")
		)
		(pad "B19" smd rect
			(at -2.29997 2.804922 90)
			(size 0.381 1.27)
			(layers "F.Cu" "F.Mask" "F.Paste")
			(net "GND")
		)
		(pad "B20" smd rect
			(at -2.29997 3.405124 90)
			(size 0.381 1.27)
			(layers "F.Cu" "F.Mask" "F.Paste")
			(net "P5E_PEX2_STN2_TX_C_DN<41>")
		)
		(pad "B21" smd rect
			(at -2.29997 4.005072 90)
			(size 0.381 1.27)
			(layers "F.Cu" "F.Mask" "F.Paste")
			(net "P5E_PEX2_STN2_TX_C_DP<41>")
		)
		(pad "B22" smd rect
			(at -2.29997 4.60502 90)
			(size 0.381 1.27)
			(layers "F.Cu" "F.Mask" "F.Paste")
			(net "GND")
		)
		(pad "B23" smd rect
			(at -2.29997 5.204968 90)
			(size 0.381 1.27)
			(layers "F.Cu" "F.Mask" "F.Paste")
			(net "P5E_PEX2_STN2_TX_C_DN<42>")
		)
		(pad "B24" smd rect
			(at -2.29997 5.804916 90)
			(size 0.381 1.27)
			(layers "F.Cu" "F.Mask" "F.Paste")
			(net "P5E_PEX2_STN2_TX_C_DP<42>")
		)
		(pad "B25" smd rect
			(at -2.29997 6.405118 90)
			(size 0.381 1.27)
			(layers "F.Cu" "F.Mask" "F.Paste")
			(net "GND")
		)
		(pad "B26" smd rect
			(at -2.29997 7.005066 90)
			(size 0.381 1.27)
			(layers "F.Cu" "F.Mask" "F.Paste")
			(net "P5E_PEX2_STN2_TX_C_DN<43>")
		)
		(pad "B27" smd rect
			(at -2.29997 7.605014 90)
			(size 0.381 1.27)
			(layers "F.Cu" "F.Mask" "F.Paste")
			(net "P5E_PEX2_STN2_TX_C_DP<43>")
		)
		(pad "B28" smd rect
			(at -2.29997 8.204962 90)
			(size 0.381 1.27)
			(layers "F.Cu" "F.Mask" "F.Paste")
			(net "GND")
		)
		(pad "G1" thru_hole oval
			(at 0 -11.364976 90)
			(size 1.6256 3.4798)
			(drill oval 1.1176 2.4638)
			(layers "*.Cu" "*.Mask")
			(remove_unused_layers no)
			(net "GND")
			(clearance 0.127)
			(thermal_gap 0.127)
		)
		(pad "G2" thru_hole oval
			(at 0 11.364976 90)
			(size 1.6256 3.4798)
			(drill oval 1.1176 2.4638)
			(layers "*.Cu" "*.Mask")
			(remove_unused_layers no)
			(net "GND")
			(clearance 0.127)
			(thermal_gap 0.127)
		)
		(zone
			(layer "F.Cu")
			(hatch none 0.5)
			(connect_pads
				(clearance 0)
			)
			(min_thickness 0.25)
			(keepout
				(tracks not_allowed)
				(vias allowed)
				(pads allowed)
				(copperpour not_allowed)
				(footprints allowed)
			)
			(placement
				(enabled no)
				(sheetname "")
			)
			(fill
				(thermal_gap 0.5)
				(thermal_bridge_width 0.5)
				(island_removal_mode 0)
			)
			(polygon
				(pts
					(xy 272.544794 -38.850062) (xy 269.794736 -38.850062) (xy 269.794736 -35.900106) (xy 272.544794 -35.900106)
				)
			)
		)
		(zone
			(layer "F.Cu")
			(hatch none 0.5)
			(connect_pads
				(clearance 0)
			)
			(min_thickness 0.25)
			(keepout
				(tracks not_allowed)
				(vias allowed)
				(pads allowed)
				(copperpour not_allowed)
				(footprints allowed)
			)
			(placement
				(enabled no)
				(sheetname "")
			)
			(fill
				(thermal_gap 0.5)
				(thermal_bridge_width 0.5)
				(island_removal_mode 0)
			)
			(polygon
				(pts
					(xy 273.614896 -17.670018) (xy 269.78483 -17.670018) (xy 269.78483 -14.720062) (xy 273.614896 -14.720062)
				)
			)
		)
		(zone
			(layers "F.Cu" "B.Cu" "In1.Cu" "In2.Cu" "In3.Cu" "In4.Cu" "In5.Cu" "In6.Cu"
				"In7.Cu" "In8.Cu" "In9.Cu" "In10.Cu" "In11.Cu" "In12.Cu" "In13.Cu" "In14.Cu"
				"In15.Cu" "In16.Cu"
			)
			(hatch none 0.5)
			(connect_pads
				(clearance 0)
			)
			(min_thickness 0.25)
			(keepout
				(tracks not_allowed)
				(vias allowed)
				(pads allowed)
				(copperpour not_allowed)
				(footprints allowed)
			)
			(placement
				(enabled no)
				(sheetname "")
			)
			(fill
				(thermal_gap 0.5)
				(thermal_bridge_width 0.5)
				(island_removal_mode 0)
			)
			(polygon
				(pts
					(arc
						(start 272.130012 -36.60013)
						(mid 270.199612 -36.60013)
						(end 272.130012 -36.60013)
					)
				)
			)
		)
		(zone
			(layers "F.Cu" "B.Cu" "In1.Cu" "In2.Cu" "In3.Cu" "In4.Cu" "In5.Cu" "In6.Cu"
				"In7.Cu" "In8.Cu" "In9.Cu" "In10.Cu" "In11.Cu" "In12.Cu" "In13.Cu" "In14.Cu"
				"In15.Cu" "In16.Cu"
			)
			(hatch none 0.5)
			(connect_pads
				(clearance 0)
			)
			(min_thickness 0.25)
			(keepout
				(tracks not_allowed)
				(vias allowed)
				(pads allowed)
				(copperpour not_allowed)
				(footprints allowed)
			)
			(placement
				(enabled no)
				(sheetname "")
			)
			(fill
				(thermal_gap 0.5)
				(thermal_bridge_width 0.5)
				(island_removal_mode 0)
			)
			(polygon
				(pts
					(arc
						(start 273.880072 -16.969994)
						(mid 271.949672 -16.969994)
						(end 273.880072 -16.969994)
					)
				)
			)
		)
	)
	(footprint ""
		(layer "F.Cu")
		(at 267.871702 -350.098614 90)
		(property "Reference" "C613"
			(at 0 0 90)
			(layer "F.SilkS")
			(hide yes)
			(effects
				(font
					(size 1.27 1.27)
				)
			)
		)
		(property "Value" ""
			(at 0 0 90)
			(layer "F.Fab")
			(effects
				(font
					(size 1.27 1.27)
				)
			)
		)
		(duplicate_pad_numbers_are_jumpers no)
		(fp_line
			(start 0.299974 -0.150114)
			(end 0.299974 0.150114)
			(stroke
				(width 0.1)
				(type default)
			)
			(layer "F.Fab")
		)
		(fp_line
			(start -0.299974 -0.150114)
			(end 0.299974 -0.150114)
			(stroke
				(width 0.1)
				(type default)
			)
			(layer "F.Fab")
		)
		(fp_line
			(start 0.299974 0.150114)
			(end -0.299974 0.150114)
			(stroke
				(width 0.1)
				(type default)
			)
			(layer "F.Fab")
		)
		(fp_line
			(start -0.299974 0.150114)
			(end -0.299974 -0.150114)
			(stroke
				(width 0.1)
				(type default)
			)
			(layer "F.Fab")
		)
		(pad "1" smd rect
			(at -0.2667 0 90)
			(size 0.3048 0.381)
			(layers "F.Cu" "F.Mask" "F.Paste")
			(net "P5E_PEX2_STN7_TX_DP<112>")
		)
		(pad "2" smd rect
			(at 0.2667 0 90)
			(size 0.3048 0.381)
			(layers "F.Cu" "F.Mask" "F.Paste")
			(net "P5E_PEX2_STN7_TX_C_DP<112>")
		)
	)
)
